# S9S_MB_2U (Grand Teton) — schematic netlist excerpt (pin names and nets, part order shuffled) for the footprints in the layout excerpt that follows; sources: Cadence DE-HDL packaged netlist, KiCad conversion of 03242023_DA0F0TMBIJ0_F0T_Motherboard_J_brd_V01_OCP.brd

C1935  Q_CAP  10UF 6.3V 20% X6S  pkg C0402  page 217 : A = P3V3_AUX_FPGA_VCCIO4 ; B = GND
R558  Q_RES  49.9 1% CHIP  pkg 0402LF  page 45 : A = SVID_ALERT0_CPU1_R_N ; B = PVNN_TERM_CPU1

(kicad_pcb
	(version 20260206)
	(generator "pcbnew")
	(generator_version "10.0")
	(general
		(thickness 1.6)
		(legacy_teardrops no)
	)
	(paper "A4")
	(title_block
		(title "03242023_DA0F0TMBIJ0_F0T_Motherboard_J_brd_V01_OCP.brd")
		(comment 1 "Grand Teton / footprints 4556-4557 of 6105")
	)
	(layers
		(0 "F.Cu" signal "TOP")
		(4 "In1.Cu" signal "GND")
		(6 "In2.Cu" signal "IN1")
		(8 "In3.Cu" signal "GND1")
		(10 "In4.Cu" signal "IN2")
		(12 "In5.Cu" signal "GND2")
		(14 "In6.Cu" signal "IN3")
		(16 "In7.Cu" signal "GND3")
		(18 "In8.Cu" signal "VCC")
		(20 "In9.Cu" signal "VCC1")
		(22 "In10.Cu" signal "GND4")
		(24 "In11.Cu" signal "IN4")
		(26 "In12.Cu" signal "GND5")
		(28 "In13.Cu" signal "IN5")
		(30 "In14.Cu" signal "GND6")
		(32 "In15.Cu" signal "IN6")
		(34 "In16.Cu" signal "GND7")
		(2 "B.Cu" signal "BOTTOM")
		(9 "F.Adhes" user "F.Adhesive")
		(11 "B.Adhes" user "B.Adhesive")
		(13 "F.Paste" user "Package Geometry/Pastemask Top")
		(15 "B.Paste" user "Package Geometry/Pastemask Bottom")
		(5 "F.SilkS" user "Ref Des/Silkscreen Top")
		(7 "B.SilkS" user "Ref Des/Silkscreen Bottom")
		(1 "F.Mask" user "Board Geometry/Soldermask Top")
		(3 "B.Mask" user "Board Geometry/Soldermask Bottom")
		(17 "Dwgs.User" user "User.Drawings")
		(19 "Cmts.User" user "User.Comments")
		(21 "Eco1.User" user "User.Eco1")
		(23 "Eco2.User" user "User.Eco2")
		(25 "Edge.Cuts" user "Board Geometry/Outline")
		(27 "Margin" user)
		(31 "F.CrtYd" user "Package Geometry/Place Bound Top")
		(29 "B.CrtYd" user "Package Geometry/Place Bound Bottom")
		(35 "F.Fab" user "Ref Des/Assembly Top")
		(33 "B.Fab" user "Ref Des/Assembly Bottom")
	)
	(footprint ""
		(layer "B.Cu")
		(at 69.404484 -190.795656 90)
		(property "Reference" "R558"
			(at 0 0 90)
			(layer "B.SilkS")
			(hide yes)
			(effects
				(font
					(size 1.27 1.27)
				)
				(justify mirror)
			)
		)
		(property "Value" ""
			(at 0 0 90)
			(layer "B.Fab")
			(effects
				(font
					(size 1.27 1.27)
				)
				(justify mirror)
			)
		)
		(duplicate_pad_numbers_are_jumpers no)
		(fp_line
			(start 0.7874 -0.4064)
			(end -0.7874 -0.4064)
			(stroke
				(width 0.1524)
				(type default)
			)
			(layer "B.SilkS")
		)
		(fp_line
			(start -0.7874 -0.4064)
			(end -0.7874 0.4064)
			(stroke
				(width 0.1524)
				(type default)
			)
			(layer "B.SilkS")
		)
		(fp_line
			(start 0.7874 0.4064)
			(end 0.7874 -0.4064)
			(stroke
				(width 0.1524)
				(type default)
			)
			(layer "B.SilkS")
		)
		(fp_line
			(start -0.7874 0.4064)
			(end 0.7874 0.4064)
			(stroke
				(width 0.1524)
				(type default)
			)
			(layer "B.SilkS")
		)
		(fp_line
			(start 0.67945 -0.305054)
			(end 0.12065 -0.305054)
			(stroke
				(width 0.1)
				(type default)
			)
			(layer "B.Fab")
		)
		(fp_line
			(start 0.12065 -0.305054)
			(end 0.12065 -0.2794)
			(stroke
				(width 0.1)
				(type default)
			)
			(layer "B.Fab")
		)
		(fp_line
			(start -0.12065 -0.3048)
			(end -0.67945 -0.3048)
			(stroke
				(width 0.1)
				(type default)
			)
			(layer "B.Fab")
		)
		(fp_line
			(start -0.67945 -0.3048)
			(end -0.67945 0.3048)
			(stroke
				(width 0.1)
				(type default)
			)
			(layer "B.Fab")
		)
		(fp_line
			(start 0.12065 -0.2794)
			(end -0.12065 -0.2794)
			(stroke
				(width 0.1)
				(type default)
			)
			(layer "B.Fab")
		)
		(fp_line
			(start -0.12065 -0.2794)
			(end -0.12065 -0.3048)
			(stroke
				(width 0.1)
				(type default)
			)
			(layer "B.Fab")
		)
		(fp_line
			(start 0.12065 0.2794)
			(end 0.12065 0.3048)
			(stroke
				(width 0.1)
				(type default)
			)
			(layer "B.Fab")
		)
		(fp_line
			(start -0.120396 0.2794)
			(end 0.12065 0.2794)
			(stroke
				(width 0.1)
				(type default)
			)
			(layer "B.Fab")
		)
		(fp_line
			(start 0.67945 0.3048)
			(end 0.67945 -0.305054)
			(stroke
				(width 0.1)
				(type default)
			)
			(layer "B.Fab")
		)
		(fp_line
			(start 0.12065 0.3048)
			(end 0.67945 0.3048)
			(stroke
				(width 0.1)
				(type default)
			)
			(layer "B.Fab")
		)
		(fp_line
			(start -0.120396 0.3048)
			(end -0.120396 0.2794)
			(stroke
				(width 0.1)
				(type default)
			)
			(layer "B.Fab")
		)
		(fp_line
			(start -0.67945 0.3048)
			(end -0.120396 0.3048)
			(stroke
				(width 0.1)
				(type default)
			)
			(layer "B.Fab")
		)
		(pad "1" smd circle
			(at 0.40005 0 270)
			(size 0 0)
			(layers "B.Cu" "B.Mask" "B.Paste")
			(net "SVID_ALERT0_CPU1_R_N")
		)
		(pad "2" smd circle
			(at -0.40005 0 270)
			(size 0 0)
			(layers "B.Cu" "B.Mask" "B.Paste")
			(net "PVNN_TERM_CPU1")
		)
	)
	(footprint ""
		(layer "B.Cu")
		(at 178.10988 -103.723948)
		(property "Reference" "C1935"
			(at 0 0 0)
			(layer "B.SilkS")
			(hide yes)
			(effects
				(font
					(size 1.27 1.27)
				)
				(justify mirror)
			)
		)
		(property "Value" ""
			(at 0 0 0)
			(layer "B.Fab")
			(effects
				(font
					(size 1.27 1.27)
				)
				(justify mirror)
			)
		)
		(duplicate_pad_numbers_are_jumpers no)
		(fp_line
			(start -0.7874 -0.4064)
			(end -0.7874 0.4064)
			(stroke
				(width 0.1524)
				(type default)
			)
			(layer "B.SilkS")
		)
		(fp_line
			(start -0.7874 0.4064)
			(end 0.7874 0.4064)
			(stroke
				(width 0.1524)
				(type default)
			)
			(layer "B.SilkS")
		)
		(fp_line
			(start 0.7874 -0.4064)
			(end -0.7874 -0.4064)
			(stroke
				(width 0.1524)
				(type default)
			)
			(layer "B.SilkS")
		)
		(fp_line
			(start 0.7874 0.4064)
			(end 0.7874 -0.4064)
			(stroke
				(width 0.1524)
				(type default)
			)
			(layer "B.SilkS")
		)
		(fp_line
			(start -0.67945 -0.3048)
			(end -0.67945 0.3048)
			(stroke
				(width 0.1)
				(type default)
			)
			(layer "B.Fab")
		)
		(fp_line
			(start -0.67945 0.3048)
			(end -0.120396 0.3048)
			(stroke
				(width 0.1)
				(type default)
			)
			(layer "B.Fab")
		)
		(fp_line
			(start -0.12065 -0.3048)
			(end -0.67945 -0.3048)
			(stroke
				(width 0.1)
				(type default)
			)
			(layer "B.Fab")
		)
		(fp_line
			(start -0.12065 -0.2794)
			(end -0.12065 -0.3048)
			(stroke
				(width 0.1)
				(type default)
			)
			(layer "B.Fab")
		)
		(fp_line
			(start -0.120396 0.2794)
			(end 0.12065 0.2794)
			(stroke
				(width 0.1)
				(type default)
			)
			(layer "B.Fab")
		)
		(fp_line
			(start -0.120396 0.3048)
			(end -0.120396 0.2794)
			(stroke
				(width 0.1)
				(type default)
			)
			(layer "B.Fab")
		)
		(fp_line
			(start 0.12065 -0.305054)
			(end 0.12065 -0.2794)
			(stroke
				(width 0.1)
				(type default)
			)
			(layer "B.Fab")
		)
		(fp_line
			(start 0.12065 -0.2794)
			(end -0.12065 -0.2794)
			(stroke
				(width 0.1)
				(type default)
			)
			(layer "B.Fab")
		)
		(fp_line
			(start 0.12065 0.2794)
			(end 0.12065 0.3048)
			(stroke
				(width 0.1)
				(type default)
			)
			(layer "B.Fab")
		)
		(fp_line
			(start 0.12065 0.3048)
			(end 0.67945 0.3048)
			(stroke
				(width 0.1)
				(type default)
			)
			(layer "B.Fab")
		)
		(fp_line
			(start 0.67945 -0.305054)
			(end 0.12065 -0.305054)
			(stroke
				(width 0.1)
				(type default)
			)
			(layer "B.Fab")
		)
		(fp_line
			(start 0.67945 0.3048)
			(end 0.67945 -0.305054)
			(stroke
				(width 0.1)
				(type default)
			)
			(layer "B.Fab")
		)
		(pad "1" smd circle
			(at 0.40005 0 180)
			(size 0 0)
			(layers "B.Cu" "B.Mask" "B.Paste")
			(net "P3V3_AUX_FPGA_VCCIO4")
		)
		(pad "2" smd circle
			(at -0.40005 0 180)
			(size 0 0)
			(layers "B.Cu" "B.Mask" "B.Paste")
			(net "GND")
		)
	)
)
